# BASEBOARD_FAB2 (Tioga Pass) — schematic netlist excerpt (pin names and nets, part order shuffled) for the footprints in the layout excerpt that follows; sources: Cadence DE-HDL packaged netlist, KiCad conversion of Wiwynn_Tioga_Pass_MB.brd

C7P5  CAP  100UF 4V 20% X5R  pkg 0805  page 76 : A = PVCCMCP_CPU1 ; B = GND
R9P10  RES  10.0K 1% CHIP  pkg 0402  page 200 : A = P3V3_STBY ; B = A_P12V_STBY_FPH_GATE
C2N9  CAP_A  1.0UF 6.3V 10% X6S  pkg 0402V  page 132 : A = PVNN_PCH_STBY ; B = GND

(kicad_pcb
	(version 20260206)
	(generator "pcbnew")
	(generator_version "10.0")
	(general
		(thickness 1.6)
		(legacy_teardrops no)
	)
	(paper "A4")
	(title_block
		(title "Wiwynn_Tioga_Pass_MB.brd")
		(comment 1 "Tioga Pass / footprints 2608-2610 of 4770")
	)
	(layers
		(0 "F.Cu" signal "TOP")
		(4 "In1.Cu" signal "L2GND")
		(6 "In2.Cu" signal "L3")
		(8 "In3.Cu" signal "L4GND")
		(10 "In4.Cu" signal "L5")
		(12 "In5.Cu" signal "L6GND")
		(14 "In6.Cu" signal "L7VCC")
		(16 "In7.Cu" signal "L8VCC")
		(18 "In8.Cu" signal "L9GND")
		(20 "In9.Cu" signal "L10")
		(22 "In10.Cu" signal "L11GND")
		(24 "In11.Cu" signal "L12")
		(26 "In12.Cu" signal "L13GND")
		(2 "B.Cu" signal "BOTTOM")
		(9 "F.Adhes" user "F.Adhesive")
		(11 "B.Adhes" user "B.Adhesive")
		(13 "F.Paste" user "Package Geometry/Pastemask Top")
		(15 "B.Paste" user "Package Geometry/Pastemask Bottom")
		(5 "F.SilkS" user "Ref Des/Silkscreen Top")
		(7 "B.SilkS" user "Ref Des/Silkscreen Bottom")
		(1 "F.Mask" user "Board Geometry/Soldermask Top")
		(3 "B.Mask" user "Board Geometry/Soldermask Bottom")
		(17 "Dwgs.User" user "User.Drawings")
		(19 "Cmts.User" user "User.Comments")
		(21 "Eco1.User" user "User.Eco1")
		(23 "Eco2.User" user "User.Eco2")
		(25 "Edge.Cuts" user "Board Geometry/Outline")
		(27 "Margin" user)
		(31 "F.CrtYd" user "Package Geometry/Place Bound Top")
		(29 "B.CrtYd" user "Package Geometry/Place Bound Bottom")
		(35 "F.Fab" user "Ref Des/Assembly Top")
		(33 "B.Fab" user "Ref Des/Assembly Bottom")
	)
	(footprint ""
		(layer "B.Cu")
		(at 112.217454 -79.575914 180)
		(property "Reference" "C7P5"
			(at 0 0 0)
			(layer "B.SilkS")
			(hide yes)
			(effects
				(font
					(size 1.27 1.27)
				)
				(justify mirror)
			)
		)
		(property "Value" ""
			(at 0 0 0)
			(layer "B.Fab")
			(effects
				(font
					(size 1.27 1.27)
				)
				(justify mirror)
			)
		)
		(duplicate_pad_numbers_are_jumpers no)
		(fp_poly
			(pts
				(xy 0.7239 -0.2159) (xy -0.7239 -0.2159) (xy -0.7239 1.9939) (xy 0.7239 1.9939)
			)
			(stroke
				(width 0)
				(type default)
			)
			(fill no)
			(layer "B.CrtYd")
		)
		(fp_line
			(start 0.7239 1.9939)
			(end -0.7239 1.9939)
			(stroke
				(width 0.1)
				(type default)
			)
			(layer "B.Fab")
		)
		(fp_line
			(start 0.7239 -0.2159)
			(end 0.7239 1.9939)
			(stroke
				(width 0.1)
				(type default)
			)
			(layer "B.Fab")
		)
		(fp_line
			(start -0.7239 1.9939)
			(end -0.7239 -0.2159)
			(stroke
				(width 0.1)
				(type default)
			)
			(layer "B.Fab")
		)
		(fp_line
			(start -0.7239 -0.2159)
			(end 0.7239 -0.2159)
			(stroke
				(width 0.1)
				(type default)
			)
			(layer "B.Fab")
		)
		(pad "1" smd rect
			(at 0 0)
			(size 1.27 1.016)
			(layers "B.Cu" "B.Mask" "B.Paste")
			(net "PVCCMCP_CPU1")
		)
		(pad "2" smd rect
			(at 0 1.778)
			(size 1.27 1.016)
			(layers "B.Cu" "B.Mask" "B.Paste")
			(net "GND")
		)
		(zone
			(layer "B.Cu")
			(hatch none 0.5)
			(connect_pads
				(clearance 0)
			)
			(min_thickness 0.25)
			(keepout
				(tracks not_allowed)
				(vias allowed)
				(pads allowed)
				(copperpour not_allowed)
				(footprints allowed)
			)
			(placement
				(enabled no)
				(sheetname "")
			)
			(fill
				(thermal_gap 0.5)
				(thermal_bridge_width 0.5)
				(island_removal_mode 0)
			)
			(polygon
				(pts
					(xy 111.582454 -80.083914) (xy 112.852454 -80.083914) (xy 112.852454 -80.845914) (xy 111.582454 -80.845914)
				)
			)
		)
	)
	(footprint ""
		(layer "B.Cu")
		(at 390.93775 -108.65485 90)
		(property "Reference" "C2N9"
			(at 0 0 90)
			(layer "B.SilkS")
			(hide yes)
			(effects
				(font
					(size 1.27 1.27)
				)
				(justify mirror)
			)
		)
		(property "Value" ""
			(at 0 0 90)
			(layer "B.Fab")
			(effects
				(font
					(size 1.27 1.27)
				)
				(justify mirror)
			)
		)
		(duplicate_pad_numbers_are_jumpers no)
		(fp_rect
			(start 0.2794 0.9144)
			(end -0.2794 -0.1143)
			(stroke
				(width 0)
				(type default)
			)
			(fill no)
			(layer "B.CrtYd")
		)
		(fp_line
			(start 0.2794 -0.1143)
			(end -0.2794 -0.1143)
			(stroke
				(width 0.1)
				(type default)
			)
			(layer "B.Fab")
		)
		(fp_line
			(start -0.2794 -0.1143)
			(end -0.2794 0.9144)
			(stroke
				(width 0.1)
				(type default)
			)
			(layer "B.Fab")
		)
		(fp_line
			(start 0.2794 0.9144)
			(end 0.2794 -0.1143)
			(stroke
				(width 0.1)
				(type default)
			)
			(layer "B.Fab")
		)
		(fp_line
			(start -0.2794 0.9144)
			(end 0.2794 0.9144)
			(stroke
				(width 0.1)
				(type default)
			)
			(layer "B.Fab")
		)
		(pad "1" smd custom
			(at 0 0)
			(size 0.10414 0.10414)
			(layers "B.Cu" "B.Mask" "B.Paste")
			(net "PVNN_PCH_STBY")
			(options
				(clearance outline)
				(anchor circle)
			)
			(primitives
				(gr_poly
					(pts
						(xy -0.20828 -0.08636) (xy -0.20828 0.08636) (xy -0.08636 0.20828) (xy 0.086614 0.20828) (xy 0.20828 0.086614)
						(xy 0.20828 -0.08636) (xy 0.08636 -0.20828) (xy -0.08636 -0.20828)
					)
					(width 0)
					(fill yes)
				)
			)
		)
		(pad "2" smd custom
			(at 0 0.8001)
			(size 0.10414 0.10414)
			(layers "B.Cu" "B.Mask" "B.Paste")
			(net "GND")
			(options
				(clearance outline)
				(anchor circle)
			)
			(primitives
				(gr_poly
					(pts
						(xy -0.20828 -0.08636) (xy -0.20828 0.08636) (xy -0.08636 0.20828) (xy 0.086614 0.20828) (xy 0.20828 0.086614)
						(xy 0.20828 -0.08636) (xy 0.08636 -0.20828) (xy -0.08636 -0.20828)
					)
					(width 0)
					(fill yes)
				)
			)
		)
		(zone
			(layer "B.Cu")
			(hatch none 0.5)
			(connect_pads
				(clearance 0)
			)
			(min_thickness 0.25)
			(keepout
				(tracks allowed)
				(vias not_allowed)
				(pads allowed)
				(copperpour not_allowed)
				(footprints allowed)
			)
			(placement
				(enabled no)
				(sheetname "")
			)
			(fill
				(thermal_gap 0.5)
				(thermal_bridge_width 0.5)
				(island_removal_mode 0)
			)
			(polygon
				(pts
					(xy 391.1473 -108.74248) (xy 391.5283 -108.74248) (xy 391.5283 -108.56722) (xy 391.1473 -108.566966)
				)
			)
		)
		(zone
			(layer "B.Cu")
			(hatch none 0.5)
			(connect_pads
				(clearance 0)
			)
			(min_thickness 0.25)
			(keepout
				(tracks not_allowed)
				(vias allowed)
				(pads allowed)
				(copperpour not_allowed)
				(footprints allowed)
			)
			(placement
				(enabled no)
				(sheetname "")
			)
			(fill
				(thermal_gap 0.5)
				(thermal_bridge_width 0.5)
				(island_removal_mode 0)
			)
			(polygon
				(pts
					(xy 391.1473 -108.74248) (xy 391.5283 -108.74248) (xy 391.5283 -108.56722) (xy 391.1473 -108.566966)
				)
			)
		)
	)
	(footprint ""
		(layer "B.Cu")
		(at 24.257 -83.185 -90)
		(property "Reference" "R9P10"
			(at 0 0 90)
			(layer "B.SilkS")
			(hide yes)
			(effects
				(font
					(size 1.27 1.27)
				)
				(justify mirror)
			)
		)
		(property "Value" ""
			(at 0 0 90)
			(layer "B.Fab")
			(effects
				(font
					(size 1.27 1.27)
				)
				(justify mirror)
			)
		)
		(duplicate_pad_numbers_are_jumpers no)
		(fp_poly
			(pts
				(xy 0.2794 -0.1016) (xy -0.2794 -0.1016) (xy -0.2794 0.9906) (xy 0.2794 0.9906)
			)
			(stroke
				(width 0)
				(type default)
			)
			(fill no)
			(layer "B.CrtYd")
		)
		(fp_line
			(start -0.2794 0.9906)
			(end -0.2794 -0.1016)
			(stroke
				(width 0.1)
				(type default)
			)
			(layer "B.Fab")
		)
		(fp_line
			(start 0.2794 0.9906)
			(end -0.2794 0.9906)
			(stroke
				(width 0.1)
				(type default)
			)
			(layer "B.Fab")
		)
		(fp_line
			(start -0.2794 -0.1016)
			(end 0.2794 -0.1016)
			(stroke
				(width 0.1)
				(type default)
			)
			(layer "B.Fab")
		)
		(fp_line
			(start 0.2794 -0.1016)
			(end 0.2794 0.9906)
			(stroke
				(width 0.1)
				(type default)
			)
			(layer "B.Fab")
		)
		(pad "1" smd rect
			(at 0 0 90)
			(size 0.508 0.508)
			(layers "B.Cu" "B.Mask" "B.Paste")
			(net "P3V3_STBY")
		)
		(pad "2" smd rect
			(at 0 0.889 90)
			(size 0.508 0.508)
			(layers "B.Cu" "B.Mask" "B.Paste")
			(net "A_P12V_STBY_FPH_GATE")
		)
		(zone
			(layer "B.Cu")
			(hatch none 0.5)
			(connect_pads
				(clearance 0)
			)
			(min_thickness 0.25)
			(keepout
				(tracks not_allowed)
				(vias allowed)
				(pads allowed)
				(copperpour not_allowed)
				(footprints allowed)
			)
			(placement
				(enabled no)
				(sheetname "")
			)
			(fill
				(thermal_gap 0.5)
				(thermal_bridge_width 0.5)
				(island_removal_mode 0)
			)
			(polygon
				(pts
					(xy 23.622 -82.931) (xy 23.622 -83.439) (xy 24.003 -83.439) (xy 24.003 -82.931)
				)
			)
		)
		(zone
			(layer "B.Cu")
			(hatch none 0.5)
			(connect_pads
				(clearance 0)
			)
			(min_thickness 0.25)
			(keepout
				(tracks allowed)
				(vias not_allowed)
				(pads allowed)
				(copperpour not_allowed)
				(footprints allowed)
			)
			(placement
				(enabled no)
				(sheetname "")
			)
			(fill
				(thermal_gap 0.5)
				(thermal_bridge_width 0.5)
				(island_removal_mode 0)
			)
			(polygon
				(pts
					(xy 24.003 -82.931) (xy 24.003 -83.439) (xy 23.622 -83.439) (xy 23.622 -82.931)
				)
			)
		)
	)
)
